# S9S_MB_2U (Grand Teton) — schematic netlist excerpt (pin names and nets, part order shuffled) for the footprints in the layout excerpt that follows; sources: Cadence DE-HDL packaged netlist, KiCad conversion of 03242023_DA0F0TMBIJ0_F0T_Motherboard_J_brd_V01_OCP.brd

PC1205  Q_CAPP  330UF 2.5V +10/-35% SPCAP  pkg SMLF  page 290 : A = PVCCFA_EHV_FIVRA_CPU1 ; B = GND
R1801  Q_RES  0 5% CHIP  pkg 0402LF  page 240 : A = PRSNT0_N ; B = GND

(kicad_pcb
	(version 20260206)
	(generator "pcbnew")
	(generator_version "10.0")
	(general
		(thickness 1.6)
		(legacy_teardrops no)
	)
	(paper "A4")
	(title_block
		(title "03242023_DA0F0TMBIJ0_F0T_Motherboard_J_brd_V01_OCP.brd")
		(comment 1 "Grand Teton / footprints 4368-4369 of 6105")
	)
	(layers
		(0 "F.Cu" signal "TOP")
		(4 "In1.Cu" signal "GND")
		(6 "In2.Cu" signal "IN1")
		(8 "In3.Cu" signal "GND1")
		(10 "In4.Cu" signal "IN2")
		(12 "In5.Cu" signal "GND2")
		(14 "In6.Cu" signal "IN3")
		(16 "In7.Cu" signal "GND3")
		(18 "In8.Cu" signal "VCC")
		(20 "In9.Cu" signal "VCC1")
		(22 "In10.Cu" signal "GND4")
		(24 "In11.Cu" signal "IN4")
		(26 "In12.Cu" signal "GND5")
		(28 "In13.Cu" signal "IN5")
		(30 "In14.Cu" signal "GND6")
		(32 "In15.Cu" signal "IN6")
		(34 "In16.Cu" signal "GND7")
		(2 "B.Cu" signal "BOTTOM")
		(9 "F.Adhes" user "F.Adhesive")
		(11 "B.Adhes" user "B.Adhesive")
		(13 "F.Paste" user "Package Geometry/Pastemask Top")
		(15 "B.Paste" user "Package Geometry/Pastemask Bottom")
		(5 "F.SilkS" user "Ref Des/Silkscreen Top")
		(7 "B.SilkS" user "Ref Des/Silkscreen Bottom")
		(1 "F.Mask" user "Board Geometry/Soldermask Top")
		(3 "B.Mask" user "Board Geometry/Soldermask Bottom")
		(17 "Dwgs.User" user "User.Drawings")
		(19 "Cmts.User" user "User.Comments")
		(21 "Eco1.User" user "User.Eco1")
		(23 "Eco2.User" user "User.Eco2")
		(25 "Edge.Cuts" user "Board Geometry/Outline")
		(27 "Margin" user)
		(31 "F.CrtYd" user "Package Geometry/Place Bound Top")
		(29 "B.CrtYd" user "Package Geometry/Place Bound Bottom")
		(35 "F.Fab" user "Ref Des/Assembly Top")
		(33 "B.Fab" user "Ref Des/Assembly Bottom")
	)
	(footprint ""
		(layer "B.Cu")
		(at 181.865016 -346.586302 -90)
		(property "Reference" "PC1205"
			(at 0 0 90)
			(layer "B.SilkS")
			(hide yes)
			(effects
				(font
					(size 1.27 1.27)
				)
				(justify mirror)
			)
		)
		(property "Value" ""
			(at 0 0 90)
			(layer "B.Fab")
			(effects
				(font
					(size 1.27 1.27)
				)
				(justify mirror)
			)
		)
		(duplicate_pad_numbers_are_jumpers no)
		(fp_line
			(start -4.533392 2.249932)
			(end 4.533392 2.249932)
			(stroke
				(width 0.1524)
				(type default)
			)
			(layer "B.SilkS")
		)
		(fp_line
			(start 4.533392 2.249932)
			(end 4.533392 -2.249932)
			(stroke
				(width 0.1524)
				(type default)
			)
			(layer "B.SilkS")
		)
		(fp_line
			(start -4.533392 -2.249932)
			(end -4.533392 2.249932)
			(stroke
				(width 0.1524)
				(type default)
			)
			(layer "B.SilkS")
		)
		(fp_line
			(start 4.533392 -2.249932)
			(end -4.533392 -2.249932)
			(stroke
				(width 0.1524)
				(type default)
			)
			(layer "B.SilkS")
		)
		(fp_poly
			(pts
				(xy 4.533392 -2.326132) (xy 5.39242 -2.326132) (xy 5.39242 2.326132) (xy 4.533392 2.326132)
			)
			(stroke
				(width 0)
				(type default)
			)
			(fill yes)
			(layer "B.SilkS")
		)
		(fp_line
			(start -3.750056 2.249932)
			(end 3.750056 2.249932)
			(stroke
				(width 0.1)
				(type default)
			)
			(layer "B.Fab")
		)
		(fp_line
			(start 3.750056 2.249932)
			(end 3.750056 -2.249932)
			(stroke
				(width 0.1)
				(type default)
			)
			(layer "B.Fab")
		)
		(fp_line
			(start -3.750056 -2.249932)
			(end -3.750056 2.249932)
			(stroke
				(width 0.1)
				(type default)
			)
			(layer "B.Fab")
		)
		(fp_line
			(start 3.750056 -2.249932)
			(end -3.750056 -2.249932)
			(stroke
				(width 0.1)
				(type default)
			)
			(layer "B.Fab")
		)
		(fp_text user "+"
			(at 6.322314 0.786384 180)
			(unlocked yes)
			(layer "B.SilkS")
			(effects
				(font
					(size 1.905 1.4224)
					(thickness 0.1524)
				)
				(justify left mirror)
			)
		)
		(fp_text user "-"
			(at -4.8514 -0.14605 270)
			(unlocked yes)
			(layer "B.SilkS")
			(effects
				(font
					(size 1.905 1.4224)
					(thickness 0.1524)
				)
				(justify left mirror)
			)
		)
		(fp_text user "+"
			(at 6.322314 0.786384 180)
			(unlocked yes)
			(layer "B.Fab")
			(effects
				(font
					(size 1.905 1.4224)
					(thickness 0.1524)
				)
				(justify left mirror)
			)
		)
		(fp_text user "-"
			(at -4.8514 -0.14605 270)
			(unlocked yes)
			(layer "B.Fab")
			(effects
				(font
					(size 1.905 1.4224)
					(thickness 0.1524)
				)
				(justify left mirror)
			)
		)
		(pad "1" smd rect
			(at 3.199892 0 90)
			(size 2.413 2.8194)
			(layers "B.Cu" "B.Mask" "B.Paste")
			(net "PVCCFA_EHV_FIVRA_CPU1")
		)
		(pad "2" smd rect
			(at -3.199892 0 90)
			(size 2.413 2.8194)
			(layers "B.Cu" "B.Mask" "B.Paste")
			(net "GND")
		)
	)
	(footprint ""
		(layer "B.Cu")
		(at 190.25108 -18.938748 180)
		(property "Reference" "R1801"
			(at 0 0 0)
			(layer "B.SilkS")
			(hide yes)
			(effects
				(font
					(size 1.27 1.27)
				)
				(justify mirror)
			)
		)
		(property "Value" ""
			(at 0 0 0)
			(layer "B.Fab")
			(effects
				(font
					(size 1.27 1.27)
				)
				(justify mirror)
			)
		)
		(duplicate_pad_numbers_are_jumpers no)
		(fp_line
			(start 0.7874 0.4064)
			(end 0.7874 -0.4064)
			(stroke
				(width 0.1524)
				(type default)
			)
			(layer "B.SilkS")
		)
		(fp_line
			(start 0.7874 -0.4064)
			(end -0.7874 -0.4064)
			(stroke
				(width 0.1524)
				(type default)
			)
			(layer "B.SilkS")
		)
		(fp_line
			(start -0.7874 0.4064)
			(end 0.7874 0.4064)
			(stroke
				(width 0.1524)
				(type default)
			)
			(layer "B.SilkS")
		)
		(fp_line
			(start -0.7874 -0.4064)
			(end -0.7874 0.4064)
			(stroke
				(width 0.1524)
				(type default)
			)
			(layer "B.SilkS")
		)
		(fp_line
			(start 0.67945 0.3048)
			(end 0.67945 -0.305054)
			(stroke
				(width 0.1)
				(type default)
			)
			(layer "B.Fab")
		)
		(fp_line
			(start 0.67945 -0.305054)
			(end 0.12065 -0.305054)
			(stroke
				(width 0.1)
				(type default)
			)
			(layer "B.Fab")
		)
		(fp_line
			(start 0.12065 0.3048)
			(end 0.67945 0.3048)
			(stroke
				(width 0.1)
				(type default)
			)
			(layer "B.Fab")
		)
		(fp_line
			(start 0.12065 0.2794)
			(end 0.12065 0.3048)
			(stroke
				(width 0.1)
				(type default)
			)
			(layer "B.Fab")
		)
		(fp_line
			(start 0.12065 -0.2794)
			(end -0.12065 -0.2794)
			(stroke
				(width 0.1)
				(type default)
			)
			(layer "B.Fab")
		)
		(fp_line
			(start 0.12065 -0.305054)
			(end 0.12065 -0.2794)
			(stroke
				(width 0.1)
				(type default)
			)
			(layer "B.Fab")
		)
		(fp_line
			(start -0.120396 0.3048)
			(end -0.120396 0.2794)
			(stroke
				(width 0.1)
				(type default)
			)
			(layer "B.Fab")
		)
		(fp_line
			(start -0.120396 0.2794)
			(end 0.12065 0.2794)
			(stroke
				(width 0.1)
				(type default)
			)
			(layer "B.Fab")
		)
		(fp_line
			(start -0.12065 -0.2794)
			(end -0.12065 -0.3048)
			(stroke
				(width 0.1)
				(type default)
			)
			(layer "B.Fab")
		)
		(fp_line
			(start -0.12065 -0.3048)
			(end -0.67945 -0.3048)
			(stroke
				(width 0.1)
				(type default)
			)
			(layer "B.Fab")
		)
		(fp_line
			(start -0.67945 0.3048)
			(end -0.120396 0.3048)
			(stroke
				(width 0.1)
				(type default)
			)
			(layer "B.Fab")
		)
		(fp_line
			(start -0.67945 -0.3048)
			(end -0.67945 0.3048)
			(stroke
				(width 0.1)
				(type default)
			)
			(layer "B.Fab")
		)
		(pad "1" smd circle
			(at 0.40005 0)
			(size 0 0)
			(layers "B.Cu" "B.Mask" "B.Paste")
			(net "PRSNT0_N")
		)
		(pad "2" smd circle
			(at -0.40005 0)
			(size 0 0)
			(layers "B.Cu" "B.Mask" "B.Paste")
			(net "GND")
		)
	)
)
